# T6G (Grand Teton) — schematic netlist excerpt (pin names and nets, part order shuffled) for the footprints in the layout excerpt that follows; sources: Cadence DE-HDL packaged netlist, KiCad conversion of 04192023_DAF0TMB3IC0_F0TG_MB_C_brd_V02_OCP.brd

R463  Q_RES  33 5% CHIP  pkg 0402LF  page 81 : A = RST_CPU0_KBRST_R_N ; B = RST_CPU0_KBRST_N
C173  Q_CAP  10UF 25V 10% X6S  pkg C0805  page 98 : A = P12V_MEM_CPU1 ; B = GND
PC426_5  Q_CAP  22UF 16V 20% X6S  pkg C0805  page 220 : A = SW_P12V_AUX_PVDDCR_CPU1_P1_FLT ; B = GND

(kicad_pcb
	(version 20260206)
	(generator "pcbnew")
	(generator_version "10.0")
	(general
		(thickness 1.6)
		(legacy_teardrops no)
	)
	(paper "A4")
	(title_block
		(title "04192023_DAF0TMB3IC0_F0TG_MB_C_brd_V02_OCP.brd")
		(comment 1 "Grand Teton / footprints 7788-7790 of 8354")
	)
	(layers
		(0 "F.Cu" signal "TOP")
		(4 "In1.Cu" signal "GND")
		(6 "In2.Cu" signal "IN1")
		(8 "In3.Cu" signal "GND1")
		(10 "In4.Cu" signal "IN2")
		(12 "In5.Cu" signal "GND2")
		(14 "In6.Cu" signal "IN3")
		(16 "In7.Cu" signal "GND3")
		(18 "In8.Cu" signal "VCC")
		(20 "In9.Cu" signal "VCC1")
		(22 "In10.Cu" signal "GND4")
		(24 "In11.Cu" signal "IN4")
		(26 "In12.Cu" signal "GND5")
		(28 "In13.Cu" signal "IN5")
		(30 "In14.Cu" signal "GND6")
		(32 "In15.Cu" signal "IN6")
		(34 "In16.Cu" signal "GND7")
		(2 "B.Cu" signal "BOTTOM")
		(9 "F.Adhes" user "F.Adhesive")
		(11 "B.Adhes" user "B.Adhesive")
		(13 "F.Paste" user "Package Geometry/Pastemask Top")
		(15 "B.Paste" user "Package Geometry/Pastemask Bottom")
		(5 "F.SilkS" user "Ref Des/Silkscreen Top")
		(7 "B.SilkS" user "Ref Des/Silkscreen Bottom")
		(1 "F.Mask" user "Board Geometry/Soldermask Top")
		(3 "B.Mask" user "Board Geometry/Soldermask Bottom")
		(17 "Dwgs.User" user "User.Drawings")
		(19 "Cmts.User" user "User.Comments")
		(21 "Eco1.User" user "User.Eco1")
		(23 "Eco2.User" user "User.Eco2")
		(25 "Edge.Cuts" user "Board Geometry/Outline")
		(27 "Margin" user)
		(31 "F.CrtYd" user "Package Geometry/Place Bound Top")
		(29 "B.CrtYd" user "Package Geometry/Place Bound Bottom")
		(35 "F.Fab" user "Ref Des/Assembly Top")
		(33 "B.Fab" user "Ref Des/Assembly Bottom")
	)
	(footprint ""
		(layer "B.Cu")
		(at 55.328058 -192.66027 180)
		(property "Reference" "C173"
			(at 0 0 0)
			(layer "B.SilkS")
			(hide yes)
			(effects
				(font
					(size 1.27 1.27)
				)
				(justify mirror)
			)
		)
		(property "Value" ""
			(at 0 0 0)
			(layer "B.Fab")
			(effects
				(font
					(size 1.27 1.27)
				)
				(justify mirror)
			)
		)
		(duplicate_pad_numbers_are_jumpers no)
		(fp_line
			(start 1.524 0.762)
			(end 1.524 -0.762)
			(stroke
				(width 0.1524)
				(type default)
			)
			(layer "B.SilkS")
		)
		(fp_line
			(start 1.524 -0.762)
			(end -1.524 -0.762)
			(stroke
				(width 0.1524)
				(type default)
			)
			(layer "B.SilkS")
		)
		(fp_line
			(start -1.524 0.762)
			(end 1.524 0.762)
			(stroke
				(width 0.1524)
				(type default)
			)
			(layer "B.SilkS")
		)
		(fp_line
			(start -1.524 -0.762)
			(end -1.524 0.762)
			(stroke
				(width 0.1524)
				(type default)
			)
			(layer "B.SilkS")
		)
		(fp_line
			(start 1.1049 0.724916)
			(end -1.1049 0.724916)
			(stroke
				(width 0.1)
				(type default)
			)
			(layer "B.Fab")
		)
		(fp_line
			(start 1.1049 -0.724916)
			(end 1.1049 0.724916)
			(stroke
				(width 0.1)
				(type default)
			)
			(layer "B.Fab")
		)
		(fp_line
			(start -1.1049 0.724916)
			(end -1.1049 -0.724916)
			(stroke
				(width 0.1)
				(type default)
			)
			(layer "B.Fab")
		)
		(fp_line
			(start -1.1049 -0.724916)
			(end 1.1049 -0.724916)
			(stroke
				(width 0.1)
				(type default)
			)
			(layer "B.Fab")
		)
		(pad "1" smd rect
			(at 0.889 0 180)
			(size 1.016 1.27)
			(layers "B.Cu" "B.Mask" "B.Paste")
			(net "P12V_MEM_CPU1")
		)
		(pad "2" smd rect
			(at -0.889 0 180)
			(size 1.016 1.27)
			(layers "B.Cu" "B.Mask" "B.Paste")
			(net "GND")
		)
	)
	(footprint ""
		(layer "B.Cu")
		(at 396.546578 -328.655172 180)
		(property "Reference" "R463"
			(at 0 0 0)
			(layer "B.SilkS")
			(hide yes)
			(effects
				(font
					(size 1.27 1.27)
				)
				(justify mirror)
			)
		)
		(property "Value" ""
			(at 0 0 0)
			(layer "B.Fab")
			(effects
				(font
					(size 1.27 1.27)
				)
				(justify mirror)
			)
		)
		(duplicate_pad_numbers_are_jumpers no)
		(fp_line
			(start 0.7874 0.4064)
			(end 0.7874 -0.4064)
			(stroke
				(width 0.1524)
				(type default)
			)
			(layer "B.SilkS")
		)
		(fp_line
			(start 0.7874 -0.4064)
			(end -0.7874 -0.4064)
			(stroke
				(width 0.1524)
				(type default)
			)
			(layer "B.SilkS")
		)
		(fp_line
			(start -0.7874 0.4064)
			(end 0.7874 0.4064)
			(stroke
				(width 0.1524)
				(type default)
			)
			(layer "B.SilkS")
		)
		(fp_line
			(start -0.7874 -0.4064)
			(end -0.7874 0.4064)
			(stroke
				(width 0.1524)
				(type default)
			)
			(layer "B.SilkS")
		)
		(fp_line
			(start 0.67945 0.3048)
			(end 0.67945 -0.305054)
			(stroke
				(width 0.1)
				(type default)
			)
			(layer "B.Fab")
		)
		(fp_line
			(start 0.67945 -0.305054)
			(end 0.12065 -0.305054)
			(stroke
				(width 0.1)
				(type default)
			)
			(layer "B.Fab")
		)
		(fp_line
			(start 0.12065 0.3048)
			(end 0.67945 0.3048)
			(stroke
				(width 0.1)
				(type default)
			)
			(layer "B.Fab")
		)
		(fp_line
			(start 0.12065 0.2794)
			(end 0.12065 0.3048)
			(stroke
				(width 0.1)
				(type default)
			)
			(layer "B.Fab")
		)
		(fp_line
			(start 0.12065 -0.2794)
			(end -0.12065 -0.2794)
			(stroke
				(width 0.1)
				(type default)
			)
			(layer "B.Fab")
		)
		(fp_line
			(start 0.12065 -0.305054)
			(end 0.12065 -0.2794)
			(stroke
				(width 0.1)
				(type default)
			)
			(layer "B.Fab")
		)
		(fp_line
			(start -0.120396 0.3048)
			(end -0.120396 0.2794)
			(stroke
				(width 0.1)
				(type default)
			)
			(layer "B.Fab")
		)
		(fp_line
			(start -0.120396 0.2794)
			(end 0.12065 0.2794)
			(stroke
				(width 0.1)
				(type default)
			)
			(layer "B.Fab")
		)
		(fp_line
			(start -0.12065 -0.2794)
			(end -0.12065 -0.3048)
			(stroke
				(width 0.1)
				(type default)
			)
			(layer "B.Fab")
		)
		(fp_line
			(start -0.12065 -0.3048)
			(end -0.67945 -0.3048)
			(stroke
				(width 0.1)
				(type default)
			)
			(layer "B.Fab")
		)
		(fp_line
			(start -0.67945 0.3048)
			(end -0.120396 0.3048)
			(stroke
				(width 0.1)
				(type default)
			)
			(layer "B.Fab")
		)
		(fp_line
			(start -0.67945 -0.3048)
			(end -0.67945 0.3048)
			(stroke
				(width 0.1)
				(type default)
			)
			(layer "B.Fab")
		)
		(pad "1" smd circle
			(at 0.40005 0)
			(size 0 0)
			(layers "B.Cu" "B.Mask" "B.Paste")
			(net "RST_CPU0_KBRST_R_N")
		)
		(pad "2" smd circle
			(at -0.40005 0)
			(size 0 0)
			(layers "B.Cu" "B.Mask" "B.Paste")
			(net "RST_CPU0_KBRST_N")
		)
	)
	(footprint ""
		(layer "B.Cu")
		(at 98.70313 -335.09712 90)
		(property "Reference" "PC426_5"
			(at 0 0 90)
			(layer "B.SilkS")
			(hide yes)
			(effects
				(font
					(size 1.27 1.27)
				)
				(justify mirror)
			)
		)
		(property "Value" ""
			(at 0 0 90)
			(layer "B.Fab")
			(effects
				(font
					(size 1.27 1.27)
				)
				(justify mirror)
			)
		)
		(duplicate_pad_numbers_are_jumpers no)
		(fp_line
			(start 1.524 -0.762)
			(end -1.524 -0.762)
			(stroke
				(width 0.1524)
				(type default)
			)
			(layer "B.SilkS")
		)
		(fp_line
			(start -1.524 -0.762)
			(end -1.524 0.762)
			(stroke
				(width 0.1524)
				(type default)
			)
			(layer "B.SilkS")
		)
		(fp_line
			(start 1.524 0.762)
			(end 1.524 -0.762)
			(stroke
				(width 0.1524)
				(type default)
			)
			(layer "B.SilkS")
		)
		(fp_line
			(start -1.524 0.762)
			(end 1.524 0.762)
			(stroke
				(width 0.1524)
				(type default)
			)
			(layer "B.SilkS")
		)
		(fp_line
			(start 1.1049 -0.724916)
			(end 1.1049 0.724916)
			(stroke
				(width 0.1)
				(type default)
			)
			(layer "B.Fab")
		)
		(fp_line
			(start -1.1049 -0.724916)
			(end 1.1049 -0.724916)
			(stroke
				(width 0.1)
				(type default)
			)
			(layer "B.Fab")
		)
		(fp_line
			(start 1.1049 0.724916)
			(end -1.1049 0.724916)
			(stroke
				(width 0.1)
				(type default)
			)
			(layer "B.Fab")
		)
		(fp_line
			(start -1.1049 0.724916)
			(end -1.1049 -0.724916)
			(stroke
				(width 0.1)
				(type default)
			)
			(layer "B.Fab")
		)
		(pad "1" smd rect
			(at 0.889 0 90)
			(size 1.016 1.27)
			(layers "B.Cu" "B.Mask" "B.Paste")
			(net "SW_P12V_AUX_PVDDCR_CPU1_P1_FLT")
		)
		(pad "2" smd rect
			(at -0.889 0 90)
			(size 1.016 1.27)
			(layers "B.Cu" "B.Mask" "B.Paste")
			(net "GND")
		)
	)
)
